# T6G (Grand Teton) — schematic netlist excerpt (pin names and nets, part order shuffled) for the footprints in the layout excerpt that follows; sources: Cadence DE-HDL packaged netlist, KiCad conversion of 04192023_DAF0TMB3IC0_F0TG_MB_C_brd_V02_OCP.brd

R870  Q_RES  4.7K 5% EMPTY  pkg 0201LF  page 342 : A = P1V8_CPU1_RT_1D ; B = RST_RT_CPU1_P2_RESET_R_N
R8081  Q_RES  0 5% CHIP  pkg 0402LF  page 86 : A = PWRGD_CHAF_CPU0_R1 ; B = PWRGD_CHAF_CPU0_R2
R3572  Q_RES  0 5% CHIP  pkg 0402LF  page 237 : A = SMB_INA230_4_3V3AUX_SCL_R ; B = SMB_INA230_4_3V3AUX_SCL_R1

(kicad_pcb
	(version 20260206)
	(generator "pcbnew")
	(generator_version "10.0")
	(general
		(thickness 1.6)
		(legacy_teardrops no)
	)
	(paper "A4")
	(title_block
		(title "04192023_DAF0TMB3IC0_F0TG_MB_C_brd_V02_OCP.brd")
		(comment 1 "Grand Teton / footprints 1875-1877 of 8354")
	)
	(layers
		(0 "F.Cu" signal "TOP")
		(4 "In1.Cu" signal "GND")
		(6 "In2.Cu" signal "IN1")
		(8 "In3.Cu" signal "GND1")
		(10 "In4.Cu" signal "IN2")
		(12 "In5.Cu" signal "GND2")
		(14 "In6.Cu" signal "IN3")
		(16 "In7.Cu" signal "GND3")
		(18 "In8.Cu" signal "VCC")
		(20 "In9.Cu" signal "VCC1")
		(22 "In10.Cu" signal "GND4")
		(24 "In11.Cu" signal "IN4")
		(26 "In12.Cu" signal "GND5")
		(28 "In13.Cu" signal "IN5")
		(30 "In14.Cu" signal "GND6")
		(32 "In15.Cu" signal "IN6")
		(34 "In16.Cu" signal "GND7")
		(2 "B.Cu" signal "BOTTOM")
		(9 "F.Adhes" user "F.Adhesive")
		(11 "B.Adhes" user "B.Adhesive")
		(13 "F.Paste" user "Package Geometry/Pastemask Top")
		(15 "B.Paste" user "Package Geometry/Pastemask Bottom")
		(5 "F.SilkS" user "Ref Des/Silkscreen Top")
		(7 "B.SilkS" user "Ref Des/Silkscreen Bottom")
		(1 "F.Mask" user "Board Geometry/Soldermask Top")
		(3 "B.Mask" user "Board Geometry/Soldermask Bottom")
		(17 "Dwgs.User" user "User.Drawings")
		(19 "Cmts.User" user "User.Comments")
		(21 "Eco1.User" user "User.Eco1")
		(23 "Eco2.User" user "User.Eco2")
		(25 "Edge.Cuts" user "Board Geometry/Outline")
		(27 "Margin" user)
		(31 "F.CrtYd" user "Package Geometry/Place Bound Top")
		(29 "B.CrtYd" user "Package Geometry/Place Bound Bottom")
		(35 "F.Fab" user "Ref Des/Assembly Top")
		(33 "B.Fab" user "Ref Des/Assembly Bottom")
	)
	(footprint ""
		(layer "F.Cu")
		(at 200.914 -104.521 180)
		(property "Reference" "R8081"
			(at 0 0 180)
			(layer "F.SilkS")
			(hide yes)
			(effects
				(font
					(size 1.27 1.27)
				)
			)
		)
		(property "Value" ""
			(at 0 0 180)
			(layer "F.Fab")
			(effects
				(font
					(size 1.27 1.27)
				)
			)
		)
		(duplicate_pad_numbers_are_jumpers no)
		(fp_line
			(start 0.7874 0.4064)
			(end -0.7874 0.4064)
			(stroke
				(width 0.1524)
				(type default)
			)
			(layer "F.SilkS")
		)
		(fp_line
			(start 0.7874 -0.4064)
			(end 0.7874 0.4064)
			(stroke
				(width 0.1524)
				(type default)
			)
			(layer "F.SilkS")
		)
		(fp_line
			(start -0.7874 0.4064)
			(end -0.7874 -0.4064)
			(stroke
				(width 0.1524)
				(type default)
			)
			(layer "F.SilkS")
		)
		(fp_line
			(start -0.7874 -0.4064)
			(end 0.7874 -0.4064)
			(stroke
				(width 0.1524)
				(type default)
			)
			(layer "F.SilkS")
		)
		(fp_line
			(start 0.67945 0.3048)
			(end 0.120396 0.3048)
			(stroke
				(width 0.1)
				(type default)
			)
			(layer "F.Fab")
		)
		(fp_line
			(start 0.67945 -0.3048)
			(end 0.67945 0.3048)
			(stroke
				(width 0.1)
				(type default)
			)
			(layer "F.Fab")
		)
		(fp_line
			(start 0.12065 -0.2794)
			(end 0.12065 -0.3048)
			(stroke
				(width 0.1)
				(type default)
			)
			(layer "F.Fab")
		)
		(fp_line
			(start 0.12065 -0.3048)
			(end 0.67945 -0.3048)
			(stroke
				(width 0.1)
				(type default)
			)
			(layer "F.Fab")
		)
		(fp_line
			(start 0.120396 0.3048)
			(end 0.120396 0.2794)
			(stroke
				(width 0.1)
				(type default)
			)
			(layer "F.Fab")
		)
		(fp_line
			(start 0.120396 0.2794)
			(end -0.12065 0.2794)
			(stroke
				(width 0.1)
				(type default)
			)
			(layer "F.Fab")
		)
		(fp_line
			(start -0.12065 0.3048)
			(end -0.67945 0.3048)
			(stroke
				(width 0.1)
				(type default)
			)
			(layer "F.Fab")
		)
		(fp_line
			(start -0.12065 0.2794)
			(end -0.12065 0.3048)
			(stroke
				(width 0.1)
				(type default)
			)
			(layer "F.Fab")
		)
		(fp_line
			(start -0.12065 -0.2794)
			(end 0.12065 -0.2794)
			(stroke
				(width 0.1)
				(type default)
			)
			(layer "F.Fab")
		)
		(fp_line
			(start -0.12065 -0.305054)
			(end -0.12065 -0.2794)
			(stroke
				(width 0.1)
				(type default)
			)
			(layer "F.Fab")
		)
		(fp_line
			(start -0.67945 0.3048)
			(end -0.67945 -0.305054)
			(stroke
				(width 0.1)
				(type default)
			)
			(layer "F.Fab")
		)
		(fp_line
			(start -0.67945 -0.305054)
			(end -0.12065 -0.305054)
			(stroke
				(width 0.1)
				(type default)
			)
			(layer "F.Fab")
		)
		(pad "1" smd circle
			(at -0.40005 0 180)
			(size 0 0)
			(layers "F.Cu" "F.Mask" "F.Paste")
			(net "PWRGD_CHAF_CPU0_R1")
		)
		(pad "2" smd circle
			(at 0.40005 0 180)
			(size 0 0)
			(layers "F.Cu" "F.Mask" "F.Paste")
			(net "PWRGD_CHAF_CPU0_R2")
		)
	)
	(footprint ""
		(layer "F.Cu")
		(at 144.315688 -395.436852 -90)
		(property "Reference" "R870"
			(at 0 0 270)
			(layer "F.SilkS")
			(hide yes)
			(effects
				(font
					(size 1.27 1.27)
				)
			)
		)
		(property "Value" ""
			(at 0 0 270)
			(layer "F.Fab")
			(effects
				(font
					(size 1.27 1.27)
				)
			)
		)
		(duplicate_pad_numbers_are_jumpers no)
		(fp_line
			(start -0.32512 0.175006)
			(end -0.32512 -0.175006)
			(stroke
				(width 0.1)
				(type default)
			)
			(layer "F.Fab")
		)
		(fp_line
			(start 0.32512 0.175006)
			(end -0.32512 0.175006)
			(stroke
				(width 0.1)
				(type default)
			)
			(layer "F.Fab")
		)
		(fp_line
			(start -0.32512 -0.175006)
			(end 0.32512 -0.175006)
			(stroke
				(width 0.1)
				(type default)
			)
			(layer "F.Fab")
		)
		(fp_line
			(start 0.32512 -0.175006)
			(end 0.32512 0.175006)
			(stroke
				(width 0.1)
				(type default)
			)
			(layer "F.Fab")
		)
		(pad "1" smd rect
			(at -0.2667 0 270)
			(size 0.3048 0.381)
			(layers "F.Cu" "F.Mask" "F.Paste")
			(net "P1V8_CPU1_RT_1D")
		)
		(pad "2" smd rect
			(at 0.2667 0 90)
			(size 0.3048 0.381)
			(layers "F.Cu" "F.Mask" "F.Paste")
			(net "RST_RT_CPU1_P2_RESET_R_N")
		)
	)
	(footprint ""
		(layer "F.Cu")
		(at 154.633422 -52.771294 90)
		(property "Reference" "R3572"
			(at 0 0 90)
			(layer "F.SilkS")
			(hide yes)
			(effects
				(font
					(size 1.27 1.27)
				)
			)
		)
		(property "Value" ""
			(at 0 0 90)
			(layer "F.Fab")
			(effects
				(font
					(size 1.27 1.27)
				)
			)
		)
		(duplicate_pad_numbers_are_jumpers no)
		(fp_line
			(start 0.7874 -0.4064)
			(end 0.7874 0.4064)
			(stroke
				(width 0.1524)
				(type default)
			)
			(layer "F.SilkS")
		)
		(fp_line
			(start -0.7874 -0.4064)
			(end 0.7874 -0.4064)
			(stroke
				(width 0.1524)
				(type default)
			)
			(layer "F.SilkS")
		)
		(fp_line
			(start 0.7874 0.4064)
			(end -0.7874 0.4064)
			(stroke
				(width 0.1524)
				(type default)
			)
			(layer "F.SilkS")
		)
		(fp_line
			(start -0.7874 0.4064)
			(end -0.7874 -0.4064)
			(stroke
				(width 0.1524)
				(type default)
			)
			(layer "F.SilkS")
		)
		(fp_line
			(start -0.12065 -0.305054)
			(end -0.12065 -0.2794)
			(stroke
				(width 0.1)
				(type default)
			)
			(layer "F.Fab")
		)
		(fp_line
			(start -0.67945 -0.305054)
			(end -0.12065 -0.305054)
			(stroke
				(width 0.1)
				(type default)
			)
			(layer "F.Fab")
		)
		(fp_line
			(start 0.67945 -0.3048)
			(end 0.67945 0.3048)
			(stroke
				(width 0.1)
				(type default)
			)
			(layer "F.Fab")
		)
		(fp_line
			(start 0.12065 -0.3048)
			(end 0.67945 -0.3048)
			(stroke
				(width 0.1)
				(type default)
			)
			(layer "F.Fab")
		)
		(fp_line
			(start 0.12065 -0.2794)
			(end 0.12065 -0.3048)
			(stroke
				(width 0.1)
				(type default)
			)
			(layer "F.Fab")
		)
		(fp_line
			(start -0.12065 -0.2794)
			(end 0.12065 -0.2794)
			(stroke
				(width 0.1)
				(type default)
			)
			(layer "F.Fab")
		)
		(fp_line
			(start 0.120396 0.2794)
			(end -0.12065 0.2794)
			(stroke
				(width 0.1)
				(type default)
			)
			(layer "F.Fab")
		)
		(fp_line
			(start -0.12065 0.2794)
			(end -0.12065 0.3048)
			(stroke
				(width 0.1)
				(type default)
			)
			(layer "F.Fab")
		)
		(fp_line
			(start 0.67945 0.3048)
			(end 0.120396 0.3048)
			(stroke
				(width 0.1)
				(type default)
			)
			(layer "F.Fab")
		)
		(fp_line
			(start 0.120396 0.3048)
			(end 0.120396 0.2794)
			(stroke
				(width 0.1)
				(type default)
			)
			(layer "F.Fab")
		)
		(fp_line
			(start -0.12065 0.3048)
			(end -0.67945 0.3048)
			(stroke
				(width 0.1)
				(type default)
			)
			(layer "F.Fab")
		)
		(fp_line
			(start -0.67945 0.3048)
			(end -0.67945 -0.305054)
			(stroke
				(width 0.1)
				(type default)
			)
			(layer "F.Fab")
		)
		(pad "1" smd circle
			(at -0.40005 0 90)
			(size 0 0)
			(layers "F.Cu" "F.Mask" "F.Paste")
			(net "SMB_INA230_4_3V3AUX_SCL_R")
		)
		(pad "2" smd circle
			(at 0.40005 0 90)
			(size 0 0)
			(layers "F.Cu" "F.Mask" "F.Paste")
			(net "SMB_INA230_4_3V3AUX_SCL_R1")
		)
	)
)
